(kicad_pcb
	(version 20260206)
	(generator "pcbnew")
	(generator_version "10.0")
	(general
		(thickness 1.6)
		(legacy_teardrops no)
	)
	(paper "A4")
	(title_block
		(title "15969-1a.1015WZS0858.brd")
		(comment 1 "Tioga Pass / footprints 14-18 of 295")
	)
	(layers
		(0 "F.Cu" signal "TOP")
		(4 "In1.Cu" signal "L2GND")
		(6 "In2.Cu" signal "L3")
		(8 "In3.Cu" signal "L4")
		(10 "In4.Cu" signal "L5GND")
		(2 "B.Cu" signal "BOTTOM")
		(9 "F.Adhes" user "F.Adhesive")
		(11 "B.Adhes" user "B.Adhesive")
		(13 "F.Paste" user "Package Geometry/Pastemask Top")
		(15 "B.Paste" user "Package Geometry/Pastemask Bottom")
		(5 "F.SilkS" user "Ref Des/Silkscreen Top")
		(7 "B.SilkS" user "Ref Des/Silkscreen Bottom")
		(1 "F.Mask" user "Board Geometry/Soldermask Top")
		(3 "B.Mask" user "Board Geometry/Soldermask Bottom")
		(17 "Dwgs.User" user "User.Drawings")
		(19 "Cmts.User" user "User.Comments")
		(21 "Eco1.User" user "User.Eco1")
		(23 "Eco2.User" user "User.Eco2")
		(25 "Edge.Cuts" user "Board Geometry/Outline")
		(27 "Margin" user)
		(31 "F.CrtYd" user "Package Geometry/Place Bound Top")
		(29 "B.CrtYd" user "Package Geometry/Place Bound Bottom")
		(35 "F.Fab" user "Ref Des/Assembly Top")
		(33 "B.Fab" user "Ref Des/Assembly Bottom")
	)
	(footprint ""
		(layer "F.Cu")
		(at 124.8664 -15.9004 -90)
		(property "Reference" "U20"
			(at 0 0 270)
			(layer "F.SilkS")
			(hide yes)
			(effects
				(font
					(size 1.27 1.27)
				)
			)
		)
		(property "Value" "PCA9555PW-GP"
			(at 0 -12.1412 270)
			(unlocked yes)
			(layer "F.Fab")
			(hide yes)
			(effects
				(font
					(size 1.016 1.016)
					(thickness 0.1524)
				)
			)
		)
		(property "Device Type" "TSOIC24H44"
			(at 0 -13.6652 270)
			(unlocked yes)
			(layer "F.Fab")
			(hide yes)
			(effects
				(font
					(size 1.016 1.016)
					(thickness 0.1524)
				)
			)
		)
		(duplicate_pad_numbers_are_jumpers no)
		(fp_line
			(start -4.0386 1.778)
			(end -4.0386 3.556)
			(stroke
				(width 0.3556)
				(type default)
			)
			(layer "F.SilkS")
		)
		(fp_line
			(start 3.683 1.778)
			(end -4.1148 1.778)
			(stroke
				(width 0.1524)
				(type default)
			)
			(layer "F.SilkS")
		)
		(fp_line
			(start -3.8354 0)
			(end -4.1148 0.2794)
			(stroke
				(width 0.1524)
				(type default)
			)
			(layer "F.SilkS")
		)
		(fp_line
			(start -3.8354 0)
			(end -4.1148 -0.2794)
			(stroke
				(width 0.1524)
				(type default)
			)
			(layer "F.SilkS")
		)
		(fp_line
			(start -4.1148 -1.778)
			(end -4.1148 1.778)
			(stroke
				(width 0.1524)
				(type default)
			)
			(layer "F.SilkS")
		)
		(fp_line
			(start -4.1148 -1.778)
			(end 3.683 -1.778)
			(stroke
				(width 0.1524)
				(type default)
			)
			(layer "F.SilkS")
		)
		(fp_line
			(start 3.683 -1.778)
			(end 3.683 1.778)
			(stroke
				(width 0.1524)
				(type default)
			)
			(layer "F.SilkS")
		)
		(fp_poly
			(pts
				(xy -3.7592 -1.778) (xy 3.683 -1.778) (xy 3.683 1.778) (xy -3.7592 1.778)
			)
			(stroke
				(width 0)
				(type default)
			)
			(fill yes)
			(layer "F.SilkS")
		)
		(fp_poly
			(pts
				(xy -4.22656 3.81) (xy 4.22656 3.81) (xy 4.22656 -3.81) (xy -4.22656 -3.81)
			)
			(stroke
				(width 0)
				(type default)
			)
			(fill no)
			(layer "F.CrtYd")
		)
		(fp_poly
			(pts
				(xy -4.22656 -3.81) (xy 4.22656 -3.81) (xy 4.22656 3.81) (xy -4.22656 3.81)
			)
			(stroke
				(width 0)
				(type default)
			)
			(fill no)
			(layer "F.Fab")
		)
		(pad "1" smd rect
			(at -3.57632 2.8194 270)
			(size 0.3556 1.524)
			(layers "F.Cu" "F.Mask" "F.Paste")
			(net "GPIO_B_EXP_INT_N")
		)
		(pad "2" smd rect
			(at -2.92608 2.8194 270)
			(size 0.3556 1.524)
			(layers "F.Cu" "F.Mask" "F.Paste")
			(net "GPIO_B_EXP_A1")
		)
		(pad "3" smd rect
			(at -2.27584 2.8194 270)
			(size 0.3556 1.524)
			(layers "F.Cu" "F.Mask" "F.Paste")
			(net "GPIO_B_EXP_A2")
		)
		(pad "4" smd rect
			(at -1.6256 2.8194 270)
			(size 0.3556 1.524)
			(layers "F.Cu" "F.Mask" "F.Paste")
			(net "PCIE_SLOT2_PRSNT2_1_N")
		)
		(pad "5" smd rect
			(at -0.97536 2.8194 270)
			(size 0.3556 1.524)
			(layers "F.Cu" "F.Mask" "F.Paste")
			(net "PCIE_SLOT2_PRSNT2_2_N")
		)
		(pad "6" smd rect
			(at -0.32512 2.8194 270)
			(size 0.3556 1.524)
			(layers "F.Cu" "F.Mask" "F.Paste")
			(net "PCIE_SLOT2_PRSNT2_3_N")
		)
		(pad "7" smd rect
			(at 0.32512 2.8194 270)
			(size 0.3556 1.524)
			(layers "F.Cu" "F.Mask" "F.Paste")
			(net "PCIE_SLOT2_PRSNT2_4_N")
		)
		(pad "8" smd rect
			(at 0.97536 2.8194 270)
			(size 0.3556 1.524)
			(layers "F.Cu" "F.Mask" "F.Paste")
			(net "PCIE_SLOT3_PRSNT2_1_N")
		)
		(pad "9" smd rect
			(at 1.6256 2.8194 270)
			(size 0.3556 1.524)
			(layers "F.Cu" "F.Mask" "F.Paste")
			(net "PCIE_SLOT3_PRSNT2_2_N")
		)
		(pad "10" smd rect
			(at 2.27584 2.8194 270)
			(size 0.3556 1.524)
			(layers "F.Cu" "F.Mask" "F.Paste")
			(net "PCIE_SLOT3_PRSNT2_3_N")
		)
		(pad "11" smd rect
			(at 2.92608 2.8194 270)
			(size 0.3556 1.524)
			(layers "F.Cu" "F.Mask" "F.Paste")
			(net "PCIE_SLOT3_PRSNT2_4_N")
		)
		(pad "12" smd rect
			(at 3.57632 2.8194 270)
			(size 0.3556 1.524)
			(layers "F.Cu" "F.Mask" "F.Paste")
			(net "GND")
		)
		(pad "13" smd rect
			(at 3.57632 -2.8194 270)
			(size 0.3556 1.524)
			(layers "F.Cu" "F.Mask" "F.Paste")
			(net "GPIO_B_IO1_0")
		)
		(pad "14" smd rect
			(at 2.92608 -2.8194 270)
			(size 0.3556 1.524)
			(layers "F.Cu" "F.Mask" "F.Paste")
			(net "FM_SLT_CFG0")
		)
		(pad "15" smd rect
			(at 2.27584 -2.8194 270)
			(size 0.3556 1.524)
			(layers "F.Cu" "F.Mask" "F.Paste")
			(net "FM_SLT_CFG1")
		)
		(pad "16" smd rect
			(at 1.6256 -2.8194 270)
			(size 0.3556 1.524)
			(layers "F.Cu" "F.Mask" "F.Paste")
			(net "GPIO_B_IO1_3")
		)
		(pad "17" smd rect
			(at 0.97536 -2.8194 270)
			(size 0.3556 1.524)
			(layers "F.Cu" "F.Mask" "F.Paste")
			(net "GPIO_B_IO1_4")
		)
		(pad "18" smd rect
			(at 0.32512 -2.8194 270)
			(size 0.3556 1.524)
			(layers "F.Cu" "F.Mask" "F.Paste")
			(net "GPIO_B_IO1_5")
		)
		(pad "19" smd rect
			(at -0.32512 -2.8194 270)
			(size 0.3556 1.524)
			(layers "F.Cu" "F.Mask" "F.Paste")
			(net "GPIO_B_IO1_6")
		)
		(pad "20" smd rect
			(at -0.97536 -2.8194 270)
			(size 0.3556 1.524)
			(layers "F.Cu" "F.Mask" "F.Paste")
			(net "GPIO_B_IO1_7")
		)
		(pad "21" smd rect
			(at -1.6256 -2.8194 270)
			(size 0.3556 1.524)
			(layers "F.Cu" "F.Mask" "F.Paste")
			(net "GPIO_B_EXP_A0")
		)
		(pad "22" smd rect
			(at -2.27584 -2.8194 270)
			(size 0.3556 1.524)
			(layers "F.Cu" "F.Mask" "F.Paste")
			(net "SMCLK_EXP_R_BMC")
		)
		(pad "23" smd rect
			(at -2.92608 -2.8194 270)
			(size 0.3556 1.524)
			(layers "F.Cu" "F.Mask" "F.Paste")
			(net "SMDAT_BMC_DEVICE")
		)
		(pad "24" smd rect
			(at -3.57632 -2.8194 270)
			(size 0.3556 1.524)
			(layers "F.Cu" "F.Mask" "F.Paste")
			(net "P3V3_STBY")
		)
	)
	(footprint ""
		(layer "F.Cu")
		(at 87.10676 -20.897088)
		(property "Reference" "U5"
			(at 0 0 0)
			(layer "F.SilkS")
			(hide yes)
			(effects
				(font
					(size 1.27 1.27)
				)
			)
		)
		(property "Value" "TPS3809K33-2-GP"
			(at 0 -4.3942 0)
			(unlocked yes)
			(layer "F.Fab")
			(hide yes)
			(effects
				(font
					(size 1.016 1.016)
					(thickness 0.1524)
				)
			)
		)
		(property "Device Type" "SOT-23-1H58"
			(at 0 -5.7912 0)
			(unlocked yes)
			(layer "F.Fab")
			(hide yes)
			(effects
				(font
					(size 1.016 1.016)
					(thickness 0.1524)
				)
			)
		)
		(duplicate_pad_numbers_are_jumpers no)
		(fp_line
			(start -1.7018 -0.254)
			(end -1.7018 0.254)
			(stroke
				(width 0.1524)
				(type default)
			)
			(layer "F.SilkS")
		)
		(fp_line
			(start -1.7018 0.254)
			(end 1.7018 0.254)
			(stroke
				(width 0.1524)
				(type default)
			)
			(layer "F.SilkS")
		)
		(fp_line
			(start 1.7018 -0.254)
			(end -1.7018 -0.254)
			(stroke
				(width 0.1524)
				(type default)
			)
			(layer "F.SilkS")
		)
		(fp_line
			(start 1.7018 0.254)
			(end 1.7018 -0.254)
			(stroke
				(width 0.1524)
				(type default)
			)
			(layer "F.SilkS")
		)
		(fp_rect
			(start -1.778 1.9812)
			(end 1.778 -1.9812)
			(stroke
				(width 0)
				(type default)
			)
			(fill no)
			(layer "F.CrtYd")
		)
		(fp_rect
			(start -1.778 1.9812)
			(end 1.778 -1.9812)
			(stroke
				(width 0)
				(type default)
			)
			(fill no)
			(layer "F.Fab")
		)
		(pad "1" smd custom
			(at -1.016 1.1176)
			(size 0.254 0.254)
			(layers "F.Cu" "F.Mask" "F.Paste")
			(net "GND")
			(options
				(clearance outline)
				(anchor circle)
			)
			(primitives
				(gr_poly
					(pts
						(arc
							(start -0.508 -0.4064)
							(mid -0.448484 -0.550084)
							(end -0.3048 -0.6096)
						)
						(arc
							(start 0.3048 -0.6096)
							(mid 0.448484 -0.550084)
							(end 0.508 -0.4064)
						)
						(arc
							(start 0.508 0.4064)
							(mid 0.448484 0.550084)
							(end 0.3048 0.6096)
						)
						(arc
							(start -0.3048 0.6096)
							(mid -0.448484 0.550084)
							(end -0.508 0.4064)
						)
					)
					(width 0)
					(fill yes)
				)
			)
		)
		(pad "2" smd custom
			(at 1.016 1.1176)
			(size 0.254 0.254)
			(layers "F.Cu" "F.Mask" "F.Paste")
			(net "RESET_O_1")
			(options
				(clearance outline)
				(anchor circle)
			)
			(primitives
				(gr_poly
					(pts
						(arc
							(start -0.508 -0.4064)
							(mid -0.448484 -0.550084)
							(end -0.3048 -0.6096)
						)
						(arc
							(start 0.3048 -0.6096)
							(mid 0.448484 -0.550084)
							(end 0.508 -0.4064)
						)
						(arc
							(start 0.508 0.4064)
							(mid 0.448484 0.550084)
							(end 0.3048 0.6096)
						)
						(arc
							(start -0.3048 0.6096)
							(mid -0.448484 0.550084)
							(end -0.508 0.4064)
						)
					)
					(width 0)
					(fill yes)
				)
			)
		)
		(pad "3" smd custom
			(at 0 -1.1176)
			(size 0.254 0.254)
			(layers "F.Cu" "F.Mask" "F.Paste")
			(net "RESET_IN")
			(options
				(clearance outline)
				(anchor circle)
			)
			(primitives
				(gr_poly
					(pts
						(arc
							(start -0.508 -0.4064)
							(mid -0.448484 -0.550084)
							(end -0.3048 -0.6096)
						)
						(arc
							(start 0.3048 -0.6096)
							(mid 0.448484 -0.550084)
							(end 0.508 -0.4064)
						)
						(arc
							(start 0.508 0.4064)
							(mid 0.448484 0.550084)
							(end 0.3048 0.6096)
						)
						(arc
							(start -0.3048 0.6096)
							(mid -0.448484 0.550084)
							(end -0.508 0.4064)
						)
					)
					(width 0)
					(fill yes)
				)
			)
		)
	)
	(footprint ""
		(layer "F.Cu")
		(at 130.2004 -19.812)
		(property "Reference" "R41"
			(at 0 0 0)
			(layer "F.SilkS")
			(hide yes)
			(effects
				(font
					(size 1.27 1.27)
				)
			)
		)
		(property "Value" "0R2F-1-GP"
			(at 0.064008 -3.993896 0)
			(unlocked yes)
			(layer "F.Fab")
			(hide yes)
			(effects
				(font
					(size 1.016 1.016)
					(thickness 0.1524)
				)
			)
		)
		(property "Device Type" "R402H16"
			(at 0.064008 -5.517896 0)
			(unlocked yes)
			(layer "F.Fab")
			(hide yes)
			(effects
				(font
					(size 1.016 1.016)
					(thickness 0.1524)
				)
			)
		)
		(duplicate_pad_numbers_are_jumpers no)
		(fp_line
			(start -0.508 -0.9398)
			(end -0.508 0.9398)
			(stroke
				(width 0.1524)
				(type default)
			)
			(layer "F.SilkS")
		)
		(fp_line
			(start 0.508 -0.9398)
			(end -0.508 -0.9398)
			(stroke
				(width 0.1524)
				(type default)
			)
			(layer "F.SilkS")
		)
		(fp_rect
			(start -0.508 0.9398)
			(end 0.508 -0.9398)
			(stroke
				(width 0)
				(type default)
			)
			(fill no)
			(layer "F.CrtYd")
		)
		(fp_rect
			(start -0.508 0.9398)
			(end 0.508 -0.9398)
			(stroke
				(width 0)
				(type default)
			)
			(fill no)
			(layer "F.Fab")
		)
		(pad "1" smd custom
			(at 0 -0.4445)
			(size 0.1397 0.1397)
			(layers "F.Cu" "F.Mask" "F.Paste")
			(net "SMCLK_BMC_DEVICE")
			(options
				(clearance outline)
				(anchor circle)
			)
			(primitives
				(gr_poly
					(pts
						(arc
							(start -0.1778 -0.2794)
							(mid -0.249642 -0.249642)
							(end -0.2794 -0.1778)
						)
						(arc
							(start -0.2794 0.1778)
							(mid -0.249642 0.249642)
							(end -0.1778 0.2794)
						)
						(arc
							(start 0.1778 0.2794)
							(mid 0.249642 0.249642)
							(end 0.2794 0.1778)
						)
						(arc
							(start 0.2794 -0.1778)
							(mid 0.249642 -0.249642)
							(end 0.1778 -0.2794)
						)
					)
					(width 0)
					(fill yes)
				)
			)
		)
		(pad "2" smd custom
			(at 0 0.4445)
			(size 0.1397 0.1397)
			(layers "F.Cu" "F.Mask" "F.Paste")
			(net "SMCLK_EXP_R_BMC")
			(options
				(clearance outline)
				(anchor circle)
			)
			(primitives
				(gr_poly
					(pts
						(arc
							(start -0.1778 -0.2794)
							(mid -0.249642 -0.249642)
							(end -0.2794 -0.1778)
						)
						(arc
							(start -0.2794 0.1778)
							(mid -0.249642 0.249642)
							(end -0.1778 0.2794)
						)
						(arc
							(start 0.1778 0.2794)
							(mid 0.249642 0.249642)
							(end 0.2794 0.1778)
						)
						(arc
							(start 0.2794 -0.1778)
							(mid 0.249642 -0.249642)
							(end 0.1778 -0.2794)
						)
					)
					(width 0)
					(fill yes)
				)
			)
		)
	)
	(footprint ""
		(layer "F.Cu")
		(at 13.97 -32.0548 180)
		(property "Reference" "C28"
			(at 0 0 180)
			(layer "F.SilkS")
			(hide yes)
			(effects
				(font
					(size 1.27 1.27)
				)
			)
		)
		(property "Value" "SCD1U25V3KX-GP"
			(at 0 -2.8194 180)
			(unlocked yes)
			(layer "F.Fab")
			(hide yes)
			(effects
				(font
					(size 1.016 1.016)
					(thickness 0.1524)
				)
			)
		)
		(property "Device Type" "C603H36"
			(at 0 -4.3434 180)
			(unlocked yes)
			(layer "F.Fab")
			(hide yes)
			(effects
				(font
					(size 1.016 1.016)
					(thickness 0.1524)
				)
			)
		)
		(duplicate_pad_numbers_are_jumpers no)
		(fp_line
			(start 0.508 0)
			(end -0.508 0)
			(stroke
				(width 0.2032)
				(type default)
			)
			(layer "F.SilkS")
		)
		(fp_rect
			(start -0.5842 1.3335)
			(end 0.5842 -1.3335)
			(stroke
				(width 0)
				(type default)
			)
			(fill no)
			(layer "F.CrtYd")
		)
		(fp_rect
			(start -0.5842 1.3335)
			(end 0.5842 -1.3335)
			(stroke
				(width 0)
				(type default)
			)
			(fill no)
			(layer "F.Fab")
		)
		(pad "1" smd custom
			(at 0 -0.762 180)
			(size 0.2159 0.2159)
			(layers "F.Cu" "F.Mask" "F.Paste")
			(net "P12V_SLOT3")
			(options
				(clearance outline)
				(anchor circle)
			)
			(primitives
				(gr_poly
					(pts
						(arc
							(start -0.3302 -0.4318)
							(mid -0.402042 -0.402042)
							(end -0.4318 -0.3302)
						)
						(arc
							(start -0.4318 0.3302)
							(mid -0.402042 0.402042)
							(end -0.3302 0.4318)
						)
						(arc
							(start 0.3302 0.4318)
							(mid 0.402042 0.402042)
							(end 0.4318 0.3302)
						)
						(arc
							(start 0.4318 -0.3302)
							(mid 0.402042 -0.402042)
							(end 0.3302 -0.4318)
						)
					)
					(width 0)
					(fill yes)
				)
			)
		)
		(pad "2" smd custom
			(at 0 0.762 180)
			(size 0.2159 0.2159)
			(layers "F.Cu" "F.Mask" "F.Paste")
			(net "GND")
			(options
				(clearance outline)
				(anchor circle)
			)
			(primitives
				(gr_poly
					(pts
						(arc
							(start -0.3302 -0.4318)
							(mid -0.402042 -0.402042)
							(end -0.4318 -0.3302)
						)
						(arc
							(start -0.4318 0.3302)
							(mid -0.402042 0.402042)
							(end -0.3302 0.4318)
						)
						(arc
							(start 0.3302 0.4318)
							(mid 0.402042 0.402042)
							(end 0.4318 0.3302)
						)
						(arc
							(start 0.4318 -0.3302)
							(mid 0.402042 -0.402042)
							(end 0.3302 -0.4318)
						)
					)
					(width 0)
					(fill yes)
				)
			)
		)
	)
	(footprint ""
		(layer "F.Cu")
		(at 16.353536 -19.63801 135)
		(property "Reference" "R81"
			(at 0 0 135)
			(layer "F.SilkS")
			(hide yes)
			(effects
				(font
					(size 1.27 1.27)
				)
			)
		)
		(property "Value" "10R2F-L-GP"
			(at 0.064119 -3.993804 135)
			(unlocked yes)
			(layer "F.Fab")
			(hide yes)
			(effects
				(font
					(size 1.016 1.016)
					(thickness 0.1524)
				)
			)
		)
		(property "Device Type" "R402H14"
			(at 0.064119 -5.517933 135)
			(unlocked yes)
			(layer "F.Fab")
			(hide yes)
			(effects
				(font
					(size 1.016 1.016)
					(thickness 0.1524)
				)
			)
		)
		(duplicate_pad_numbers_are_jumpers no)
		(fp_line
			(start 0.508103 -0.939874)
			(end -0.507923 -0.939694)
			(stroke
				(width 0.1524)
				(type default)
			)
			(layer "F.SilkS")
		)
		(fp_line
			(start -0.507923 -0.939694)
			(end -0.507923 0.939694)
			(stroke
				(width 0.1524)
				(type default)
			)
			(layer "F.SilkS")
		)
		(fp_poly
			(pts
				(xy -0.507923 -0.939906) (xy 0.508077 -0.939905) (xy 0.508076 0.939694) (xy -0.507923 0.939694)
			)
			(stroke
				(width 0)
				(type default)
			)
			(fill no)
			(layer "F.CrtYd")
		)
		(fp_poly
			(pts
				(xy -0.507923 -0.939906) (xy 0.508077 -0.939905) (xy 0.508076 0.939694) (xy -0.507923 0.939694)
			)
			(stroke
				(width 0)
				(type default)
			)
			(fill no)
			(layer "F.Fab")
		)
		(pad "1" smd custom
			(at 0 -0.4445 135)
			(size 0.1397 0.1397)
			(layers "F.Cu" "F.Mask" "F.Paste")
			(net "P12V_SLOT2")
			(options
				(clearance outline)
				(anchor circle)
			)
			(primitives
				(gr_poly
					(pts
						(arc
							(start -0.1778 -0.2794)
							(mid -0.249642 -0.249642)
							(end -0.2794 -0.1778)
						)
						(arc
							(start -0.2794 0.1778)
							(mid -0.249642 0.249642)
							(end -0.1778 0.2794)
						)
						(arc
							(start 0.1778 0.2794)
							(mid 0.249642 0.249642)
							(end 0.2794 0.1778)
						)
						(arc
							(start 0.2794 -0.1778)
							(mid 0.249642 -0.249642)
							(end 0.1778 -0.2794)
						)
					)
					(width 0)
					(fill yes)
				)
			)
		)
		(pad "2" smd custom
			(at 0 0.4445 135)
			(size 0.1397 0.1397)
			(layers "F.Cu" "F.Mask" "F.Paste")
			(net "SLOT2_P12V_SENSE_VN_R")
			(options
				(clearance outline)
				(anchor circle)
			)
			(primitives
				(gr_poly
					(pts
						(arc
							(start -0.1778 -0.2794)
							(mid -0.249642 -0.249642)
							(end -0.2794 -0.1778)
						)
						(arc
							(start -0.2794 0.1778)
							(mid -0.249642 0.249642)
							(end -0.1778 0.2794)
						)
						(arc
							(start 0.1778 0.2794)
							(mid 0.249642 0.249642)
							(end 0.2794 0.1778)
						)
						(arc
							(start 0.2794 -0.1778)
							(mid 0.249642 -0.249642)
							(end 0.1778 -0.2794)
						)
					)
					(width 0)
					(fill yes)
				)
			)
		)
	)
)
